FILE_TYPE = CONNECTIVITY;
{Allegro Design Entry HDL 17.2-2016 S081 (4005846) 1/11/2022}
"PAGE_NUMBER" = 105;
0"NC";
1"M_I_CPU1_SA_CB<7:0>";
2"M_I_CPU1_SA_CA<6:0>";
3"M_I_CPU1_SB_CA<6:0>";
4"M_I_CPU1_SB_CB<7:0>";
5"M_I_CPU1_SA_DQ<31:0>";
6"M_I_CPU1_SB_DQ<31:0>";
7"M_I_CPU1_SA_DQS_DN<9:0>";
8"M_I_CPU1_SA_DQS_DP<9:0>";
9"M_I_CPU1_SB_DQS_DN<9:0>";
10"M_I_CPU1_SB_DQS_DP<9:0>";
11"GND\g";
12"GND\g";
13"P3V3_STBY\g";
14"I3C_SPD_DDRGL_CPU1_SCL";
15"I3C_SPD_DDRI_CPU1_SCL";
16"PWRGD_CHI_CPU1_DIMM";
17"TP_CHI_CPU1_DIMM_RFU_5";
18"PWRGD_CHGL_CPU1";
19"TP_CHI_CPU1_DIMM_RFU_6";
20"I3C_SPD_DDRGL_CPU1_SDA";
21"PD_CHI_CPU1_DIMM_SAA";
22"P3V3_STBY\g";
23"P12V_MEM_1\g";
24"GND\g";
25"GND\g";
26"M_I_CPU1_SB_DQS_DP<9>";
27"M_I_CPU1_SB_DQS_DN<9>";
28"M_I_CPU1_SA_DQS_DP<9>";
29"M_I_CPU1_SA_DQS_DN<9>";
30"M_I_CPU1_SA_DQS_DP<8>";
31"M_I_CPU1_SA_DQS_DN<8>";
32"M_I_CPU1_SB_DQS_DN<7>";
33"M_I_CPU1_SA_DQS_DP<7>";
34"M_I_CPU1_SB_DQS_DP<6>";
35"M_I_CPU1_SB_DQS_DN<6>";
36"M_I_CPU1_SA_DQS_DN<6>";
37"M_I_CPU1_SB_DQS_DP<5>";
38"M_I_CPU1_SB_DQS_DN<5>";
39"M_I_CPU1_SA_DQS_DP<5>";
40"M_I_CPU1_SA_DQS_DN<5>";
41"M_I_CPU1_SB_DQS_DP<4>";
42"M_I_CPU1_SB_DQS_DN<4>";
43"M_I_CPU1_SA_DQS_DP<4>";
44"M_I_CPU1_SA_DQS_DN<4>";
45"M_I_CPU1_SB_DQS_DP<3>";
46"M_I_CPU1_SB_DQS_DN<3>";
47"M_I_CPU1_SA_DQS_DP<3>";
48"M_I_CPU1_SA_DQS_DN<3>";
49"M_I_CPU1_SB_DQS_DP<2>";
50"M_I_CPU1_SB_DQS_DN<2>";
51"M_I_CPU1_SA_DQS_DP<2>";
52"M_I_CPU1_SA_DQS_DN<2>";
53"M_I_CPU1_SB_DQS_DP<1>";
54"M_I_CPU1_SB_DQS_DN<1>";
55"M_I_CPU1_SA_DQS_DP<1>";
56"M_I_CPU1_SA_DQS_DN<1>";
57"M_I_CPU1_SB_DQS_DP<0>";
58"M_I_CPU1_SB_DQS_DN<0>";
59"M_I_CPU1_SA_DQS_DP<0>";
60"M_I_CPU1_SA_DQS_DN<0>";
61"M_I_CPU1_SB_DQS_DP<7>";
62"M_I_CPU1_SB_DQS_DN<8>";
63"M_I_CPU1_SB_DQS_DP<8>";
64"M_I_CPU1_SA_DQS_DP<6>";
65"M_I_CPU1_SA_DQS_DN<7>";
66"M_I_CPU1_SA_DQ<31>";
67"TP_CHI_CPU1_DIMM_RFU_0";
68"TP_CHI_CPU1_DIMM_RFU_1";
69"TP_CHI_CPU1_DIMM_RFU_2";
70"TP_CHI_CPU1_DIMM_RFU_3";
71"TP_CHI_CPU1_DIMM_RFU_4";
72"M_I_CPU1_RESET_N";
73"M_I_CPU1_SB_PAR";
74"M_I_CPU1_SA_PAR";
75"M_I_CPU1_SB_RSP<0>";
76"M_I_CPU1_SA_RSP<0>";
77"M_I_CPU1_SB_DQ<0>";
78"M_I_CPU1_SB_DQ<1>";
79"M_I_CPU1_SB_DQ<2>";
80"M_I_CPU1_SB_DQ<3>";
81"M_I_CPU1_SB_DQ<4>";
82"M_I_CPU1_SB_DQ<5>";
83"M_I_CPU1_SB_DQ<6>";
84"M_I_CPU1_SB_DQ<7>";
85"M_I_CPU1_SB_DQ<8>";
86"M_I_CPU1_SB_DQ<9>";
87"M_I_CPU1_SB_DQ<10>";
88"M_I_CPU1_SB_DQ<11>";
89"M_I_CPU1_SB_DQ<12>";
90"M_I_CPU1_SB_DQ<13>";
91"M_I_CPU1_SB_DQ<14>";
92"M_I_CPU1_SB_DQ<15>";
93"M_I_CPU1_SB_DQ<16>";
94"M_I_CPU1_SB_DQ<17>";
95"M_I_CPU1_SB_DQ<18>";
96"M_I_CPU1_SB_DQ<19>";
97"M_I_CPU1_SB_DQ<20>";
98"M_I_CPU1_SB_DQ<21>";
99"M_I_CPU1_SB_DQ<22>";
100"M_I_CPU1_SB_DQ<23>";
101"M_I_CPU1_SB_DQ<24>";
102"M_I_CPU1_SB_DQ<25>";
103"M_I_CPU1_SB_DQ<26>";
104"M_I_CPU1_SB_DQ<27>";
105"M_I_CPU1_SB_DQ<28>";
106"M_I_CPU1_SB_DQ<29>";
107"M_I_CPU1_SB_DQ<30>";
108"M_I_CPU1_SB_DQ<31>";
109"M_I_CPU1_SA_DQ<0>";
110"M_I_CPU1_SA_DQ<1>";
111"M_I_CPU1_SA_DQ<2>";
112"M_I_CPU1_SA_DQ<3>";
113"M_I_CPU1_SA_DQ<4>";
114"M_I_CPU1_SA_DQ<5>";
115"M_I_CPU1_SA_DQ<6>";
116"M_I_CPU1_SA_DQ<7>";
117"M_I_CPU1_SA_DQ<8>";
118"M_I_CPU1_SA_DQ<9>";
119"M_I_CPU1_SA_DQ<10>";
120"M_I_CPU1_SA_DQ<11>";
121"M_I_CPU1_SA_DQ<12>";
122"M_I_CPU1_SA_DQ<13>";
123"M_I_CPU1_SA_DQ<14>";
124"M_I_CPU1_SA_DQ<15>";
125"M_I_CPU1_SA_DQ<16>";
126"M_I_CPU1_SA_DQ<17>";
127"M_I_CPU1_SA_DQ<18>";
128"M_I_CPU1_SA_DQ<19>";
129"M_I_CPU1_SA_DQ<20>";
130"M_I_CPU1_SA_DQ<21>";
131"M_I_CPU1_SA_DQ<22>";
132"M_I_CPU1_SA_DQ<23>";
133"M_I_CPU1_SA_DQ<24>";
134"M_I_CPU1_SA_DQ<25>";
135"M_I_CPU1_SA_DQ<26>";
136"M_I_CPU1_SA_DQ<27>";
137"M_I_CPU1_SA_DQ<28>";
138"M_I_CPU1_SA_DQ<29>";
139"M_I_CPU1_SA_DQ<30>";
140"M_I_CPU1_SB_CS_N<1>";
141"M_I_CPU1_SA_CS_N<1>";
142"M_I_CPU1_SB_CS_N<0>";
143"M_I_CPU1_SA_CS_N<0>";
144"M_I_CPU1_CLK_DP<0>";
145"M_I_CPU1_CLK_DN<0>";
146"M_I_CPU1_SB_CB<0>";
147"M_I_CPU1_SB_CB<1>";
148"M_I_CPU1_SB_CB<2>";
149"M_I_CPU1_SB_CB<3>";
150"M_I_CPU1_SB_CB<4>";
151"M_I_CPU1_SB_CB<5>";
152"M_I_CPU1_SB_CB<6>";
153"M_I_CPU1_SA_CB<0>";
154"M_I_CPU1_SA_CB<2>";
155"M_I_CPU1_SA_CB<3>";
156"M_I_CPU1_SA_CB<5>";
157"M_I_CPU1_SA_CB<6>";
158"M_I_CPU1_SB_CA<6>";
159"M_I_CPU1_SA_CA<6>";
160"M_I_CPU1_SB_CA<5>";
161"M_I_CPU1_SA_CA<5>";
162"M_I_CPU1_SB_CA<4>";
163"M_I_CPU1_SA_CA<4>";
164"M_I_CPU1_SB_CA<3>";
165"M_I_CPU1_SA_CA<3>";
166"M_I_CPU1_SB_CA<2>";
167"M_I_CPU1_SA_CA<2>";
168"M_I_CPU1_SB_CA<1>";
169"M_I_CPU1_SA_CA<1>";
170"M_I_CPU1_SB_CA<0>";
171"M_I_CPU1_SA_CA<0>";
172"M_I_CPU1_ALERT_N";
173"M_I_CPU1_SB_CB<7>";
174"M_I_CPU1_SA_CB<1>";
175"M_I_CPU1_SA_CB<4>";
176"M_I_CPU1_SA_CB<7>";
177"GND\g";
178"PD_CHI_CPU1_DIMM_SAA";
%"TAP"
"1","(-5975,4150)","0","mstr_standard","I100";
;
CDS_LIB"mstr_standard"
BODY_TYPE"PLUMBING"
HDL_TAP"TRUE";
"B \NAC \NWC"5;
"S \NAC"
BN"7"116;
%"TAP"
"1","(-5975,4300)","0","mstr_standard","I101";
;
CDS_LIB"mstr_standard"
BODY_TYPE"PLUMBING"
HDL_TAP"TRUE";
"B \NAC \NWC"5;
"S \NAC"
BN"10"119;
%"TAP"
"1","(-5975,4250)","0","mstr_standard","I102";
;
CDS_LIB"mstr_standard"
BODY_TYPE"PLUMBING"
HDL_TAP"TRUE";
"B \NAC \NWC"5;
"S \NAC"
BN"9"118;
%"TAP"
"1","(-5975,4200)","0","mstr_standard","I103";
;
CDS_LIB"mstr_standard"
BODY_TYPE"PLUMBING"
HDL_TAP"TRUE";
"B \NAC \NWC"5;
"S \NAC"
BN"8"117;
%"TAP"
"1","(-5975,4350)","0","mstr_standard","I104";
;
CDS_LIB"mstr_standard"
BODY_TYPE"PLUMBING"
HDL_TAP"TRUE";
"B \NAC \NWC"5;
"S \NAC"
BN"11"120;
%"TAP"
"1","(-5975,4400)","0","mstr_standard","I105";
;
CDS_LIB"mstr_standard"
BODY_TYPE"PLUMBING"
HDL_TAP"TRUE";
"B \NAC \NWC"5;
"S \NAC"
BN"12"121;
%"TAP"
"1","(-5975,4450)","0","mstr_standard","I106";
;
CDS_LIB"mstr_standard"
BODY_TYPE"PLUMBING"
HDL_TAP"TRUE";
"B \NAC \NWC"5;
"S \NAC"
BN"13"122;
%"TAP"
"1","(-5975,4500)","0","mstr_standard","I107";
;
CDS_LIB"mstr_standard"
BODY_TYPE"PLUMBING"
HDL_TAP"TRUE";
"B \NAC \NWC"5;
"S \NAC"
BN"14"123;
%"TAP"
"1","(-5975,4550)","0","mstr_standard","I108";
;
CDS_LIB"mstr_standard"
BODY_TYPE"PLUMBING"
HDL_TAP"TRUE";
"B \NAC \NWC"5;
"S \NAC"
BN"15"124;
%"TAP"
"1","(-5975,4650)","0","mstr_standard","I109";
;
CDS_LIB"mstr_standard"
BODY_TYPE"PLUMBING"
HDL_TAP"TRUE";
"B \NAC \NWC"5;
"S \NAC"
BN"17"126;
%"TAP"
"1","(-5975,4600)","0","mstr_standard","I110";
;
CDS_LIB"mstr_standard"
BODY_TYPE"PLUMBING"
HDL_TAP"TRUE";
"B \NAC \NWC"5;
"S \NAC"
BN"16"125;
%"TAP"
"1","(-5975,4800)","0","mstr_standard","I111";
;
CDS_LIB"mstr_standard"
BODY_TYPE"PLUMBING"
HDL_TAP"TRUE";
"B \NAC \NWC"5;
"S \NAC"
BN"20"129;
%"TAP"
"1","(-5975,4750)","0","mstr_standard","I112";
;
CDS_LIB"mstr_standard"
BODY_TYPE"PLUMBING"
HDL_TAP"TRUE";
"B \NAC \NWC"5;
"S \NAC"
BN"19"128;
%"TAP"
"1","(-5975,4700)","0","mstr_standard","I113";
;
CDS_LIB"mstr_standard"
BODY_TYPE"PLUMBING"
HDL_TAP"TRUE";
"B \NAC \NWC"5;
"S \NAC"
BN"18"127;
%"TAP"
"1","(-5975,4900)","0","mstr_standard","I114";
;
CDS_LIB"mstr_standard"
BODY_TYPE"PLUMBING"
HDL_TAP"TRUE";
"B \NAC \NWC"5;
"S \NAC"
BN"22"131;
%"TAP"
"1","(-5975,4850)","0","mstr_standard","I115";
;
CDS_LIB"mstr_standard"
BODY_TYPE"PLUMBING"
HDL_TAP"TRUE";
"B \NAC \NWC"5;
"S \NAC"
BN"21"130;
%"TAP"
"1","(-5975,5050)","0","mstr_standard","I116";
;
CDS_LIB"mstr_standard"
BODY_TYPE"PLUMBING"
HDL_TAP"TRUE";
"B \NAC \NWC"5;
"S \NAC"
BN"25"134;
%"TAP"
"1","(-5975,5000)","0","mstr_standard","I117";
;
CDS_LIB"mstr_standard"
BODY_TYPE"PLUMBING"
HDL_TAP"TRUE";
"B \NAC \NWC"5;
"S \NAC"
BN"24"133;
%"TAP"
"1","(-5975,4950)","0","mstr_standard","I118";
;
CDS_LIB"mstr_standard"
BODY_TYPE"PLUMBING"
HDL_TAP"TRUE";
"B \NAC \NWC"5;
"S \NAC"
BN"23"132;
%"TAP"
"1","(-5975,5150)","0","mstr_standard","I119";
;
CDS_LIB"mstr_standard"
BODY_TYPE"PLUMBING"
HDL_TAP"TRUE";
"B \NAC \NWC"5;
"S \NAC"
BN"27"136;
%"TAP"
"1","(-5975,5200)","0","mstr_standard","I120";
;
CDS_LIB"mstr_standard"
BODY_TYPE"PLUMBING"
HDL_TAP"TRUE";
"B \NAC \NWC"5;
"S \NAC"
BN"28"137;
%"TAP"
"1","(-5975,5100)","0","mstr_standard","I121";
;
CDS_LIB"mstr_standard"
BODY_TYPE"PLUMBING"
HDL_TAP"TRUE";
"B \NAC \NWC"5;
"S \NAC"
BN"26"135;
%"TAP"
"1","(-5975,5300)","0","mstr_standard","I122";
;
CDS_LIB"mstr_standard"
BODY_TYPE"PLUMBING"
HDL_TAP"TRUE";
"B \NAC \NWC"5;
"S \NAC"
BN"30"139;
%"TAP"
"1","(-5975,5250)","0","mstr_standard","I123";
;
CDS_LIB"mstr_standard"
BODY_TYPE"PLUMBING"
HDL_TAP"TRUE";
"B \NAC \NWC"5;
"S \NAC"
BN"29"138;
%"TAP"
"1","(-5975,5350)","0","mstr_standard","I124";
;
CDS_LIB"mstr_standard"
BODY_TYPE"PLUMBING"
HDL_TAP"TRUE";
"B \NAC \NWC"5;
"S \NAC"
BN"31"66;
%"GND"
"1","(-6375,925)","0","mstr_symbols","I127";
;
SIZE"1B"
CDS_LIB"mstr_symbols"
BOM_COST"MEM"
BODY_TYPE"PLUMBING"
VOLTAGE"0.0"
HDL_POWER"GND";
"A\NAC"11;
%"Q_RES"
"2","(-6375,1150)","0","pure_quanta","I128";
;
LOCATION"R775"
$SEC"1"
CDS_SEC"1"
WATTAGE"1/16W"
MATERIAL"CHIP"
TOLERANCE"1%"
VALUE"23.2K"
PART_NUMBER"TMP_QCS32322FB11"
PACK_TYPE"0402LF"
CDS_LIB"pure_quanta";
"A"
$PN"1"178;
"B"
$PN"2"11;
%"GND"
"1","(-2125,1825)","0","mstr_symbols","I140";
;
SIZE"1B"
CDS_LIB"mstr_symbols"
BODY_TYPE"PLUMBING"
VOLTAGE"0.0"
HDL_POWER"GND";
"A\NAC"25;
%"GND"
"1","(-325,1600)","0","mstr_symbols","I141";
;
SIZE"1B"
CDS_LIB"mstr_symbols"
BODY_TYPE"PLUMBING"
VOLTAGE"0.0"
HDL_POWER"GND";
"A\NAC"24;
%"SCONN288_DDR506112002KQ"
"3","(-1225,3600)","0","pure_quanta","I176";
;
LOCATION"J100"
$SEC"3"
CDS_SEC"3"
PART_TYPE"SMLF"
MATERIAL"IO"
PART_NUMBER"DFHST8FS479"
VALUE"SCONN288_DDR506112002KQ"
CDS_LMAN_SYM_OUTLINE"-450,1800,450,-1750"
NEEDS_NO_SIZE"TRUE"
CDS_LIB"pure_quanta";
"G3"
$PN"G3"24;
"G2"
$PN"G2"24;
"G1"
$PN"G1"24;
"VSS62"
$PN"141"24;
"VSS61"
$PN"139"24;
"VSS60"
$PN"136"24;
"VSS58"
$PN"132"24;
"VSS104"
$PN"240"25;
"VSS102"
$PN"235"25;
"VSS100"
$PN"230"25;
"VIN_BULK2"
$PN"146"23;
"VIN_BULK1"
$PN"145"23;
"VIN_BULK0"
$PN"1"23;
"VSS126"
$PN"288"25;
"VSS125"
$PN"286"25;
"VSS124"
$PN"284"25;
"VSS123"
$PN"281"25;
"VSS122"
$PN"279"25;
"VSS121"
$PN"277"25;
"VSS120"
$PN"275"25;
"VSS119"
$PN"273"25;
"VSS118"
$PN"270"25;
"VSS117"
$PN"268"25;
"VSS116"
$PN"266"25;
"VSS115"
$PN"264"25;
"VSS114"
$PN"262"25;
"VSS113"
$PN"259"25;
"VSS112"
$PN"257"25;
"VSS111"
$PN"255"25;
"VSS110"
$PN"253"25;
"VSS109"
$PN"251"25;
"VSS108"
$PN"248"25;
"VSS107"
$PN"246"25;
"VSS106"
$PN"244"25;
"VSS105"
$PN"242"25;
"VSS103"
$PN"237"25;
"VSS101"
$PN"233"25;
"VSS99"
$PN"228"25;
"VSS98"
$PN"226"25;
"VSS97"
$PN"224"25;
"VSS96"
$PN"222"25;
"VSS95"
$PN"219"25;
"VSS94"
$PN"216"25;
"VSS93"
$PN"214"25;
"VSS92"
$PN"212"25;
"VSS91"
$PN"210"25;
"VSS90"
$PN"208"25;
"VSS89"
$PN"206"25;
"VSS88"
$PN"204"25;
"VSS87"
$PN"202"25;
"VSS86"
$PN"199"25;
"VSS85"
$PN"197"25;
"VSS84"
$PN"195"25;
"VSS83"
$PN"193"25;
"VSS82"
$PN"191"25;
"VSS81"
$PN"188"25;
"VSS80"
$PN"186"25;
"VSS79"
$PN"184"25;
"VSS78"
$PN"182"25;
"VSS77"
$PN"180"25;
"VSS76"
$PN"177"25;
"VSS75"
$PN"175"25;
"VSS74"
$PN"173"25;
"VSS73"
$PN"171"25;
"VSS72"
$PN"169"25;
"VSS71"
$PN"166"25;
"VSS70"
$PN"164"25;
"VSS69"
$PN"162"25;
"VSS68"
$PN"160"25;
"VSS67"
$PN"158"25;
"VSS66"
$PN"155"25;
"VSS65"
$PN"153"25;
"VSS64"
$PN"151"25;
"VSS63"
$PN"143"24;
"VSS59"
$PN"134"24;
"VSS57"
$PN"130"24;
"VSS56"
$PN"128"24;
"VSS55"
$PN"125"24;
"VSS54"
$PN"123"24;
"VSS53"
$PN"121"24;
"VSS52"
$PN"119"24;
"VSS51"
$PN"117"24;
"VSS50"
$PN"114"24;
"VSS49"
$PN"112"24;
"VSS48"
$PN"110"24;
"VSS47"
$PN"108"24;
"VSS46"
$PN"106"24;
"VSS45"
$PN"103"24;
"VSS44"
$PN"101"24;
"VSS43"
$PN"99"24;
"VSS42"
$PN"97"24;
"VSS41"
$PN"95"24;
"VSS40"
$PN"92"24;
"VSS39"
$PN"90"24;
"VSS38"
$PN"88"24;
"VSS37"
$PN"85"24;
"VSS36"
$PN"83"24;
"VSS35"
$PN"81"24;
"VSS34"
$PN"79"24;
"VSS33"
$PN"77"24;
"VSS32"
$PN"75"24;
"VSS31"
$PN"73"24;
"VSS30"
$PN"71"24;
"VSS29"
$PN"69"24;
"VSS28"
$PN"67"24;
"VSS27"
$PN"65"24;
"VSS26"
$PN"63"24;
"VSS25"
$PN"61"24;
"VSS24"
$PN"59"24;
"VSS23"
$PN"57"24;
"VSS22"
$PN"54"24;
"VSS21"
$PN"52"24;
"VSS20"
$PN"50"24;
"VSS19"
$PN"48"24;
"VSS18"
$PN"46"24;
"VSS17"
$PN"43"24;
"VSS16"
$PN"41"24;
"VSS15"
$PN"39"24;
"VSS14"
$PN"37"24;
"VSS13"
$PN"35"24;
"VSS12"
$PN"32"24;
"VSS11"
$PN"30"24;
"VSS10"
$PN"28"24;
"VSS9"
$PN"26"24;
"VSS8"
$PN"24"24;
"VSS7"
$PN"21"24;
"VSS6"
$PN"19"24;
"VSS5"
$PN"17"24;
"VSS4"
$PN"15"24;
"VSS3"
$PN"13"24;
"VSS2"
$PN"10"24;
"VSS1"
$PN"8"24;
"VSS0"
$PN"6"24;
%"Q_CAP"
"1","(-8550,3175)","2","pure_quanta","I185";
;
LOCATION"C168"
$SEC"1"
CDS_SEC"1"
MATERIAL"X7R"
TOLERANCE"10%"
VALUE"0.1UF"
PART_NUMBER"CH4104K1B00"
VOLTAGE"25V"
PACK_TYPE"0402"
BOM_COST"MEM"
CDS_LIB"pure_quanta"
ROOM"MEM_CH_A_CPU0_DIMM1";
"B"
$PN"2"12;
"A"
$PN"1"22;
%"GND"
"1","(-8550,2950)","0","mstr_symbols","I186";
;
BOM_COST"MEM"
SIZE"1B"
CDS_LIB"mstr_symbols"
BODY_TYPE"PLUMBING"
VOLTAGE"0"
ROOM"MEM_EFGH_DECOUPLING_CAPS"
HDL_POWER"GND";
"A\NAC"12;
%"Q_RES"
"1","(-8475,2100)","2","pure_quanta","I188";
;
LOCATION"R311"
$SEC"1"
CDS_SEC"1"
VALUE"0"
CDS_LIB"pure_quanta"
BOM_COST"MEM"
WATTAGE"1/16W"
MATERIAL"CHIP"
TOLERANCE"5%"
PART_NUMBER"CS00002JB38"
PACK_TYPE"0402LF"
ROOM"RST_CPU0_PLD_TO_DIMM";
"B"
$PN"2"18;
"A"
$PN"1"16;
%"VCC_CORE"
"1","(-8350,2425)","0","mstr_symbols","I189";
;
HDL_POWER"P3V3_STBY"
CDS_LIB"mstr_symbols"
VOLTAGE"3.3"
ROOM"PVCCINFAON_CPU0_CTRL";
"A"13;
%"Q_RES"
"2","(-8350,2250)","0","pure_quanta","I190";
;
LOCATION"R112"
$SEC"1"
CDS_SEC"1"
WATTAGE"1/16W"
MATERIAL"EMPTY"
TOLERANCE"5%"
VALUE"1K"
PACK_TYPE"0402LF"
CDS_LIB"pure_quanta"
BOM_COST"MEM"
PART_NUMBER"TMP_QCS21002JB34"
ROOM"MEM_CH_A_CPU0_DIMM1";
"A"
$PN"1"13;
"B"
$PN"2"16;
%"TAP"
"1","(-3250,3100)","0","mstr_standard","I191";
;
CDS_LIB"mstr_standard"
BODY_TYPE"PLUMBING"
HDL_TAP"TRUE";
"B \NAC \NWC"9;
"S \NAC"
BN"7"32;
%"TAP"
"1","(-3250,3300)","0","mstr_standard","I192";
;
CDS_LIB"mstr_standard"
BODY_TYPE"PLUMBING"
HDL_TAP"TRUE";
"B \NAC \NWC"9;
"S \NAC"
BN"9"27;
%"TAP"
"1","(-3250,3450)","0","mstr_standard","I193";
;
CDS_LIB"mstr_standard"
BODY_TYPE"PLUMBING"
HDL_TAP"TRUE";
"B \NAC \NWC"7;
"S \NAC"
BN"0"60;
%"TAP"
"1","(-3250,3550)","0","mstr_standard","I194";
;
CDS_LIB"mstr_standard"
BODY_TYPE"PLUMBING"
HDL_TAP"TRUE";
"B \NAC \NWC"7;
"S \NAC"
BN"1"56;
%"TAP"
"1","(-3450,3800)","0","mstr_standard","I195";
;
CDS_LIB"mstr_standard"
BODY_TYPE"PLUMBING"
HDL_TAP"TRUE";
"B \NAC \NWC"8;
"S \NAC"
BN"3"47;
%"TAP"
"1","(-3250,4350)","0","mstr_standard","I201";
;
CDS_LIB"mstr_standard"
BODY_TYPE"PLUMBING"
HDL_TAP"TRUE";
"B \NAC \NWC"7;
"S \NAC"
BN"9"29;
%"TAP"
"1","(-3450,4400)","0","mstr_standard","I202";
;
CDS_LIB"mstr_standard"
BODY_TYPE"PLUMBING"
HDL_TAP"TRUE";
"B \NAC \NWC"8;
"S \NAC"
BN"9"28;
%"TAP"
"1","(-3450,4300)","0","mstr_standard","I203";
;
CDS_LIB"mstr_standard"
BODY_TYPE"PLUMBING"
HDL_TAP"TRUE";
"B \NAC \NWC"8;
"S \NAC"
BN"8"30;
%"TAP"
"1","(-3250,4250)","0","mstr_standard","I204";
;
CDS_LIB"mstr_standard"
BODY_TYPE"PLUMBING"
HDL_TAP"TRUE";
"B \NAC \NWC"7;
"S \NAC"
BN"8"31;
%"TAP"
"1","(-3250,4150)","0","mstr_standard","I205";
;
CDS_LIB"mstr_standard"
BODY_TYPE"PLUMBING"
HDL_TAP"TRUE";
"B \NAC \NWC"7;
"S \NAC"
BN"7"65;
%"TAP"
"1","(-3250,4050)","0","mstr_standard","I206";
;
CDS_LIB"mstr_standard"
BODY_TYPE"PLUMBING"
HDL_TAP"TRUE";
"B \NAC \NWC"7;
"S \NAC"
BN"6"36;
%"TAP"
"1","(-3250,3950)","0","mstr_standard","I207";
;
CDS_LIB"mstr_standard"
BODY_TYPE"PLUMBING"
HDL_TAP"TRUE";
"B \NAC \NWC"7;
"S \NAC"
BN"5"40;
%"TAP"
"1","(-3250,3850)","0","mstr_standard","I208";
;
CDS_LIB"mstr_standard"
BODY_TYPE"PLUMBING"
HDL_TAP"TRUE";
"B \NAC \NWC"7;
"S \NAC"
BN"4"44;
%"TAP"
"1","(-3250,3650)","0","mstr_standard","I209";
;
CDS_LIB"mstr_standard"
BODY_TYPE"PLUMBING"
HDL_TAP"TRUE";
"B \NAC \NWC"7;
"S \NAC"
BN"2"52;
%"TAP"
"1","(-3250,3750)","0","mstr_standard","I210";
;
CDS_LIB"mstr_standard"
BODY_TYPE"PLUMBING"
HDL_TAP"TRUE";
"B \NAC \NWC"7;
"S \NAC"
BN"3"48;
%"TAP"
"1","(-3450,4200)","0","mstr_standard","I211";
;
CDS_LIB"mstr_standard"
BODY_TYPE"PLUMBING"
HDL_TAP"TRUE";
"B \NAC \NWC"8;
"S \NAC"
BN"7"33;
%"TAP"
"1","(-3450,4100)","0","mstr_standard","I212";
;
CDS_LIB"mstr_standard"
BODY_TYPE"PLUMBING"
HDL_TAP"TRUE";
"B \NAC \NWC"8;
"S \NAC"
BN"6"64;
%"TAP"
"1","(-3450,3900)","0","mstr_standard","I213";
;
CDS_LIB"mstr_standard"
BODY_TYPE"PLUMBING"
HDL_TAP"TRUE";
"B \NAC \NWC"8;
"S \NAC"
BN"4"43;
%"TAP"
"1","(-3450,4000)","0","mstr_standard","I214";
;
CDS_LIB"mstr_standard"
BODY_TYPE"PLUMBING"
HDL_TAP"TRUE";
"B \NAC \NWC"8;
"S \NAC"
BN"5"39;
%"TAP"
"1","(-3450,3700)","0","mstr_standard","I215";
;
CDS_LIB"mstr_standard"
BODY_TYPE"PLUMBING"
HDL_TAP"TRUE";
"B \NAC \NWC"8;
"S \NAC"
BN"2"51;
%"TAP"
"1","(-3450,3600)","0","mstr_standard","I216";
;
CDS_LIB"mstr_standard"
BODY_TYPE"PLUMBING"
HDL_TAP"TRUE";
"B \NAC \NWC"8;
"S \NAC"
BN"1"55;
%"TAP"
"1","(-3450,3500)","0","mstr_standard","I217";
;
CDS_LIB"mstr_standard"
BODY_TYPE"PLUMBING"
HDL_TAP"TRUE";
"B \NAC \NWC"8;
"S \NAC"
BN"0"59;
%"TAP"
"1","(-3450,3250)","0","mstr_standard","I218";
;
CDS_LIB"mstr_standard"
BODY_TYPE"PLUMBING"
HDL_TAP"TRUE";
"B \NAC \NWC"10;
"S \NAC"
BN"8"63;
%"TAP"
"1","(-3450,3350)","0","mstr_standard","I219";
;
CDS_LIB"mstr_standard"
BODY_TYPE"PLUMBING"
HDL_TAP"TRUE";
"B \NAC \NWC"10;
"S \NAC"
BN"9"26;
%"SCONN288_DDR506112002KQ"
"1","(-6825,3600)","0","pure_quanta","I22";
;
LOCATION"J100"
$SEC"1"
CDS_SEC"1"
PART_TYPE"SMLF"
MATERIAL"IO"
VALUE"SCONN288_DDR506112002KQ"
PART_NUMBER"DFHST8FS479"
CDS_LMAN_SYM_OUTLINE"-450,1900,450,-1850"
NEEDS_NO_SIZE"TRUE"
CDS_LIB"pure_quanta";
"PWR_GOOD||FAIL_N"
$PN"147"16;
"DQ31_A"
$PN"194"66;
"CB7_A"
$PN"205"176;
"CB4_A"
$PN"58"175;
"CB1_A"
$PN"53"174;
"CB7_B"
$PN"236"173;
"ALERT_N \B"
$PN"62"172;
"CA0_A"
$PN"66"171;
"CA0_B"
$PN"76"170;
"CA1_A"
$PN"211"169;
"CA1_B"
$PN"221"168;
"CA2_A"
$PN"68"167;
"CA2_B"
$PN"78"166;
"CA3_A"
$PN"213"165;
"CA3_B"
$PN"223"164;
"CA4_A"
$PN"70"163;
"CA4_B"
$PN"80"162;
"CA5_A"
$PN"215"161;
"CA5_B"
$PN"225"160;
"CA6_A"
$PN"72"159;
"CA6_B"
$PN"82"158;
"CB6_A"
$PN"203"157;
"CB5_A"
$PN"60"156;
"CB3_A"
$PN"198"155;
"CB2_A"
$PN"196"154;
"CB0_A"
$PN"51"153;
"CB6_B"
$PN"234"152;
"CB5_B"
$PN"91"151;
"CB4_B"
$PN"89"150;
"CB3_B"
$PN"243"149;
"CB2_B"
$PN"241"148;
"CB1_B"
$PN"98"147;
"CB0_B"
$PN"96"146;
"CK_C \B"
$PN"218"145;
"CK_T"
$PN"217"144;
"CS0_A_N"
$PN"64"143;
"CS0_B_N"
$PN"84"142;
"CS1_A_N"
$PN"209"141;
"CS1_B_N"
$PN"229"140;
"DQ30_A"
$PN"192"139;
"DQ29_A"
$PN"49"138;
"DQ28_A"
$PN"47"137;
"DQ27_A"
$PN"187"136;
"DQ26_A"
$PN"185"135;
"DQ25_A"
$PN"42"134;
"DQ24_A"
$PN"40"133;
"DQ23_A"
$PN"183"132;
"DQ22_A"
$PN"181"131;
"DQ21_A"
$PN"38"130;
"DQ20_A"
$PN"36"129;
"DQ19_A"
$PN"176"128;
"DQ18_A"
$PN"174"127;
"DQ17_A"
$PN"31"126;
"DQ16_A"
$PN"29"125;
"DQ15_A"
$PN"172"124;
"DQ14_A"
$PN"170"123;
"DQ13_A"
$PN"27"122;
"DQ12_A"
$PN"25"121;
"DQ11_A"
$PN"165"120;
"DQ10_A"
$PN"163"119;
"DQ9_A"
$PN"20"118;
"DQ8_A"
$PN"18"117;
"DQ7_A"
$PN"161"116;
"DQ6_A"
$PN"159"115;
"DQ5_A"
$PN"16"114;
"DQ4_A"
$PN"14"113;
"DQ3_A"
$PN"154"112;
"DQ2_A"
$PN"152"111;
"DQ1_A"
$PN"9"110;
"DQ0_A"
$PN"7"109;
"DQ31_B"
$PN"287"108;
"DQ30_B"
$PN"285"107;
"DQ29_B"
$PN"142"106;
"DQ28_B"
$PN"140"105;
"DQ27_B"
$PN"280"104;
"DQ26_B"
$PN"278"103;
"DQ25_B"
$PN"135"102;
"DQ24_B"
$PN"133"101;
"DQ23_B"
$PN"276"100;
"DQ22_B"
$PN"274"99;
"DQ21_B"
$PN"131"98;
"DQ20_B"
$PN"129"97;
"DQ19_B"
$PN"269"96;
"DQ18_B"
$PN"267"95;
"DQ17_B"
$PN"124"94;
"DQ16_B"
$PN"122"93;
"DQ15_B"
$PN"265"92;
"DQ14_B"
$PN"263"91;
"DQ13_B"
$PN"120"90;
"DQ12_B"
$PN"118"89;
"DQ11_B"
$PN"258"88;
"DQ10_B"
$PN"256"87;
"DQ9_B"
$PN"113"86;
"DQ8_B"
$PN"111"85;
"DQ7_B"
$PN"254"84;
"DQ6_B"
$PN"252"83;
"DQ5_B"
$PN"109"82;
"DQ4_B"
$PN"107"81;
"DQ3_B"
$PN"247"80;
"DQ2_B"
$PN"245"79;
"DQ1_B"
$PN"102"78;
"DQ0_B"
$PN"100"77;
"HAS"
$PN"148"21;
"HSCL"
$PN"4"15;
"HSDA"
$PN"5"20;
"LBD||RSP_A_N"
$PN"86"76;
"LBS||RSP_B_N"
$PN"87"75;
"PAR_A"
$PN"74"74;
"PAR_B"
$PN"227"73;
"RESET_N \B"
$PN"207"72;
"RFU6"
$PN"232"19;
"RFU5"
$PN"231"17;
"RFU4"
$PN"220"71;
"RFU3"
$PN"150"70;
"RFU2"
$PN"149"69;
"RFU1"
$PN"144"68;
"RFU0"
$PN"2"67;
"VIN_MGMT"
$PN"3"22;
%"TAP"
"1","(-3250,3200)","0","mstr_standard","I220";
;
CDS_LIB"mstr_standard"
BODY_TYPE"PLUMBING"
HDL_TAP"TRUE";
"B \NAC \NWC"9;
"S \NAC"
BN"8"62;
%"TAP"
"1","(-3250,3000)","0","mstr_standard","I221";
;
CDS_LIB"mstr_standard"
BODY_TYPE"PLUMBING"
HDL_TAP"TRUE";
"B \NAC \NWC"9;
"S \NAC"
BN"6"35;
%"TAP"
"1","(-3250,2900)","0","mstr_standard","I222";
;
CDS_LIB"mstr_standard"
BODY_TYPE"PLUMBING"
HDL_TAP"TRUE";
"B \NAC \NWC"9;
"S \NAC"
BN"5"38;
%"TAP"
"1","(-3250,2800)","0","mstr_standard","I223";
;
CDS_LIB"mstr_standard"
BODY_TYPE"PLUMBING"
HDL_TAP"TRUE";
"B \NAC \NWC"9;
"S \NAC"
BN"4"42;
%"TAP"
"1","(-3250,2700)","0","mstr_standard","I224";
;
CDS_LIB"mstr_standard"
BODY_TYPE"PLUMBING"
HDL_TAP"TRUE";
"B \NAC \NWC"9;
"S \NAC"
BN"3"46;
%"TAP"
"1","(-3250,2600)","0","mstr_standard","I225";
;
CDS_LIB"mstr_standard"
BODY_TYPE"PLUMBING"
HDL_TAP"TRUE";
"B \NAC \NWC"9;
"S \NAC"
BN"2"50;
%"TAP"
"1","(-3250,2500)","0","mstr_standard","I226";
;
CDS_LIB"mstr_standard"
BODY_TYPE"PLUMBING"
HDL_TAP"TRUE";
"B \NAC \NWC"9;
"S \NAC"
BN"1"54;
%"TAP"
"1","(-3250,2400)","0","mstr_standard","I227";
;
CDS_LIB"mstr_standard"
BODY_TYPE"PLUMBING"
HDL_TAP"TRUE";
"B \NAC \NWC"9;
"S \NAC"
BN"0"58;
%"TAP"
"1","(-3450,3150)","0","mstr_standard","I228";
;
CDS_LIB"mstr_standard"
BODY_TYPE"PLUMBING"
HDL_TAP"TRUE";
"B \NAC \NWC"10;
"S \NAC"
BN"7"61;
%"TAP"
"1","(-3450,3050)","0","mstr_standard","I229";
;
CDS_LIB"mstr_standard"
BODY_TYPE"PLUMBING"
HDL_TAP"TRUE";
"B \NAC \NWC"10;
"S \NAC"
BN"6"34;
%"TAP"
"1","(-7675,3150)","2","mstr_standard","I23";
;
CDS_LIB"mstr_standard"
BODY_TYPE"PLUMBING"
HDL_TAP"TRUE";
"B \NAC \NWC"4;
"S \NAC"
BN"0"146;
%"TAP"
"1","(-3450,2950)","0","mstr_standard","I230";
;
CDS_LIB"mstr_standard"
BODY_TYPE"PLUMBING"
HDL_TAP"TRUE";
"B \NAC \NWC"10;
"S \NAC"
BN"5"37;
%"TAP"
"1","(-3450,2750)","0","mstr_standard","I231";
;
CDS_LIB"mstr_standard"
BODY_TYPE"PLUMBING"
HDL_TAP"TRUE";
"B \NAC \NWC"10;
"S \NAC"
BN"3"45;
%"TAP"
"1","(-3450,2850)","0","mstr_standard","I232";
;
CDS_LIB"mstr_standard"
BODY_TYPE"PLUMBING"
HDL_TAP"TRUE";
"B \NAC \NWC"10;
"S \NAC"
BN"4"41;
%"TAP"
"1","(-3450,2650)","0","mstr_standard","I233";
;
CDS_LIB"mstr_standard"
BODY_TYPE"PLUMBING"
HDL_TAP"TRUE";
"B \NAC \NWC"10;
"S \NAC"
BN"2"49;
%"TAP"
"1","(-3450,2550)","0","mstr_standard","I234";
;
CDS_LIB"mstr_standard"
BODY_TYPE"PLUMBING"
HDL_TAP"TRUE";
"B \NAC \NWC"10;
"S \NAC"
BN"1"53;
%"TAP"
"1","(-3450,2450)","0","mstr_standard","I235";
;
CDS_LIB"mstr_standard"
BODY_TYPE"PLUMBING"
HDL_TAP"TRUE";
"B \NAC \NWC"10;
"S \NAC"
BN"0"57;
%"SCONN288_DDR506112002KQ"
"2","(-4400,3400)","0","pure_quanta","I236";
;
LOCATION"J100"
$SEC"2"
CDS_SEC"2"
MATERIAL"IO"
VALUE"SCONN288_DDR506112002KQ"
PART_TYPE"SMLF"
PART_NUMBER"DFHST8FS479"
CDS_LMAN_SYM_OUTLINE"-600,1150,600,-1150"
NEEDS_NO_SIZE"TRUE"
CDS_LIB"pure_quanta";
"DQS7_A_C||TDQS7_A_C \B"
$PN"178"65;
"DQS6_A_T||TDQS6_A_T"
$PN"168"64;
"DQS8_B_T||TDQS8_B_T"
$PN"283"63;
"DQS8_B_C||TDQS8_B_C \B"
$PN"282"62;
"DQS7_B_T||TDQS7_B_T"
$PN"272"61;
"DQS0_A_C \B"
$PN"12"60;
"DQS0_A_T"
$PN"11"59;
"DQS0_B_C \B"
$PN"105"58;
"DQS0_B_T"
$PN"104"57;
"DQS1_A_C \B"
$PN"23"56;
"DQS1_A_T"
$PN"22"55;
"DQS1_B_C \B"
$PN"116"54;
"DQS1_B_T"
$PN"115"53;
"DQS2_A_C \B"
$PN"34"52;
"DQS2_A_T"
$PN"33"51;
"DQS2_B_C \B"
$PN"127"50;
"DQS2_B_T"
$PN"126"49;
"DQS3_A_C \B"
$PN"45"48;
"DQS3_A_T"
$PN"44"47;
"DQS3_B_C \B"
$PN"138"46;
"DQS3_B_T"
$PN"137"45;
"DQS4_A_C \B"
$PN"56"44;
"DQS4_A_T"
$PN"55"43;
"DQS4_B_C \B"
$PN"238"42;
"DQS4_B_T"
$PN"239"41;
"DQS5_A_C||TDQS5_A_C||DQS5_A_T||TDQS5_A_T \B"
$PN"156"40;
"DQS5_A_T||TDQS5_A_T"
$PN"157"39;
"DQS5_B_C||TDQS5_B_C \B"
$PN"249"38;
"DQS5_B_T||TDQS5_B_T"
$PN"250"37;
"DQS6_A_C||TDQS6_A_C||DQS6_A_T||TDQS6_A_T \B"
$PN"167"36;
"DQS6_B_C||TDQS6_B_C \B"
$PN"260"35;
"DQS6_B_T||TDQS6_B_T"
$PN"261"34;
"DQS7_A_T||TDQS7_A_T"
$PN"179"33;
"DQS7_B_C||TDQS7_B_C \B"
$PN"271"32;
"DQS8_A_C||TDQS8_A_C \B"
$PN"189"31;
"DQS8_A_T||TDQS8_A_T"
$PN"190"30;
"DQS9_A_C||TDQS9_A_C \B"
$PN"200"29;
"DQS9_A_T||TDQS9_A_T"
$PN"201"28;
"DQS9_B_C||TDQS9_B_C \B"
$PN"94"27;
"DQS9_B_T||TDQS9_B_T||DBI4_B_N"
$PN"93"26;
%"GND"
"1","(-2825,5450)","0","pure_quanta_power","I237";
;
CDS_LIB"pure_quanta_power"
BOM_COST"MEM"
SIZE"1B"
ROOM"MEM_EFGH_DECOUPLING_CAPS"
HDL_POWER"GND";
"A<SIZE-1..0>\NAC"177;
%"Q_CAP"
"1","(-2825,5800)","2","pure_quanta","I238";
;
LOCATION"C534"
$SEC"1"
CDS_SEC"1"
MATERIAL"X6S"
TOLERANCE"10%"
PART_NUMBER"CH6104KEA00"
VOLTAGE"25V"
PACK_TYPE"C0805"
VALUE"10UF"
BOM_COST"MEM"
CDS_LIB"pure_quanta"
ROOM"MEM_CH_A_CPU0_DIMM1";
"B"
$PN"2"177;
"A"
$PN"1"23;
%"Q_CAP"
"1","(-2250,5800)","2","pure_quanta","I239";
;
LOCATION"C535"
$SEC"1"
CDS_SEC"1"
MATERIAL"X6S"
TOLERANCE"10%"
VALUE"10UF"
PART_NUMBER"CH6104KEA00"
VOLTAGE"25V"
PACK_TYPE"C0805"
BOM_COST"MEM"
CDS_LIB"pure_quanta"
ROOM"MEM_CH_A_CPU0_DIMM1";
"B"
$PN"2"177;
"A"
$PN"1"23;
%"TAP"
"1","(-7675,3200)","2","mstr_standard","I24";
;
CDS_LIB"mstr_standard"
BODY_TYPE"PLUMBING"
HDL_TAP"TRUE";
"B \NAC \NWC"4;
"S \NAC"
BN"1"147;
%"UNIVERSAL_POWER"
"1","(-2825,6125)","0","pure_quanta_power","I240";
;
HDL_POWER"P12V_MEM_1"
CDS_LIB"pure_quanta_power";
"A"23;
%"Q_RES"
"1","(-7725,2625)","0","pure_quanta","I242";
;
$LOCATION"R1588"
CDS_LOCATION"R1588"
$SEC"1"
CDS_SEC"1"
VALUE"49.9"
CDS_LIB"pure_quanta"
PART_NUMBER"CS04992FB07"
TOLERANCE"1%"
WATTAGE"1/16W"
PACK_TYPE"0402LF"
MATERIAL"CHIP";
"B"
$PN"2"15;
"A"
$PN"1"14;
%"TAP"
"1","(-7675,3250)","2","mstr_standard","I25";
;
CDS_LIB"mstr_standard"
BODY_TYPE"PLUMBING"
HDL_TAP"TRUE";
"B \NAC \NWC"4;
"S \NAC"
BN"2"148;
%"TAP"
"1","(-7675,3300)","2","mstr_standard","I26";
;
CDS_LIB"mstr_standard"
BODY_TYPE"PLUMBING"
HDL_TAP"TRUE";
"B \NAC \NWC"4;
"S \NAC"
BN"3"149;
%"TAP"
"1","(-7675,3350)","2","mstr_standard","I27";
;
CDS_LIB"mstr_standard"
BODY_TYPE"PLUMBING"
HDL_TAP"TRUE";
"B \NAC \NWC"4;
"S \NAC"
BN"4"150;
%"TAP"
"1","(-7675,3400)","2","mstr_standard","I28";
;
CDS_LIB"mstr_standard"
BODY_TYPE"PLUMBING"
HDL_TAP"TRUE";
"B \NAC \NWC"4;
"S \NAC"
BN"5"151;
%"TAP"
"1","(-7675,3450)","2","mstr_standard","I29";
;
CDS_LIB"mstr_standard"
BODY_TYPE"PLUMBING"
HDL_TAP"TRUE";
"B \NAC \NWC"4;
"S \NAC"
BN"6"152;
%"TAP"
"1","(-7675,3500)","2","mstr_standard","I30";
;
CDS_LIB"mstr_standard"
BODY_TYPE"PLUMBING"
HDL_TAP"TRUE";
"B \NAC \NWC"4;
"S \NAC"
BN"7"173;
%"TAP"
"1","(-7675,3600)","2","mstr_standard","I31";
;
CDS_LIB"mstr_standard"
BODY_TYPE"PLUMBING"
HDL_TAP"TRUE";
"B \NAC \NWC"1;
"S \NAC"
BN"0"153;
%"TAP"
"1","(-7675,3650)","2","mstr_standard","I32";
;
CDS_LIB"mstr_standard"
BODY_TYPE"PLUMBING"
HDL_TAP"TRUE";
"B \NAC \NWC"1;
"S \NAC"
BN"1"174;
%"TAP"
"1","(-7675,3750)","2","mstr_standard","I33";
;
CDS_LIB"mstr_standard"
BODY_TYPE"PLUMBING"
HDL_TAP"TRUE";
"B \NAC \NWC"1;
"S \NAC"
BN"3"155;
%"TAP"
"1","(-7675,3700)","2","mstr_standard","I34";
;
CDS_LIB"mstr_standard"
BODY_TYPE"PLUMBING"
HDL_TAP"TRUE";
"B \NAC \NWC"1;
"S \NAC"
BN"2"154;
%"TAP"
"1","(-5975,2150)","0","mstr_standard","I35";
;
CDS_LIB"mstr_standard"
BODY_TYPE"PLUMBING"
HDL_TAP"TRUE";
"B \NAC \NWC"6;
"S \NAC"
BN"0"77;
%"TAP"
"1","(-5975,2250)","0","mstr_standard","I36";
;
CDS_LIB"mstr_standard"
BODY_TYPE"PLUMBING"
HDL_TAP"TRUE";
"B \NAC \NWC"6;
"S \NAC"
BN"2"79;
%"TAP"
"1","(-5975,2200)","0","mstr_standard","I37";
;
CDS_LIB"mstr_standard"
BODY_TYPE"PLUMBING"
HDL_TAP"TRUE";
"B \NAC \NWC"6;
"S \NAC"
BN"1"78;
%"TAP"
"1","(-5975,2350)","0","mstr_standard","I38";
;
CDS_LIB"mstr_standard"
BODY_TYPE"PLUMBING"
HDL_TAP"TRUE";
"B \NAC \NWC"6;
"S \NAC"
BN"4"81;
%"TAP"
"1","(-5975,2300)","0","mstr_standard","I39";
;
CDS_LIB"mstr_standard"
BODY_TYPE"PLUMBING"
HDL_TAP"TRUE";
"B \NAC \NWC"6;
"S \NAC"
BN"3"80;
%"TAP"
"1","(-5975,2400)","0","mstr_standard","I40";
;
CDS_LIB"mstr_standard"
BODY_TYPE"PLUMBING"
HDL_TAP"TRUE";
"B \NAC \NWC"6;
"S \NAC"
BN"5"82;
%"TAP"
"1","(-5975,2450)","0","mstr_standard","I41";
;
CDS_LIB"mstr_standard"
BODY_TYPE"PLUMBING"
HDL_TAP"TRUE";
"B \NAC \NWC"6;
"S \NAC"
BN"6"83;
%"TAP"
"1","(-5975,2500)","0","mstr_standard","I42";
;
CDS_LIB"mstr_standard"
BODY_TYPE"PLUMBING"
HDL_TAP"TRUE";
"B \NAC \NWC"6;
"S \NAC"
BN"7"84;
%"TAP"
"1","(-5975,2600)","0","mstr_standard","I43";
;
CDS_LIB"mstr_standard"
BODY_TYPE"PLUMBING"
HDL_TAP"TRUE";
"B \NAC \NWC"6;
"S \NAC"
BN"9"86;
%"TAP"
"1","(-5975,2550)","0","mstr_standard","I44";
;
CDS_LIB"mstr_standard"
BODY_TYPE"PLUMBING"
HDL_TAP"TRUE";
"B \NAC \NWC"6;
"S \NAC"
BN"8"85;
%"TAP"
"1","(-5975,2650)","0","mstr_standard","I45";
;
CDS_LIB"mstr_standard"
BODY_TYPE"PLUMBING"
HDL_TAP"TRUE";
"B \NAC \NWC"6;
"S \NAC"
BN"10"87;
%"TAP"
"1","(-5975,2750)","0","mstr_standard","I46";
;
CDS_LIB"mstr_standard"
BODY_TYPE"PLUMBING"
HDL_TAP"TRUE";
"B \NAC \NWC"6;
"S \NAC"
BN"12"89;
%"TAP"
"1","(-5975,2700)","0","mstr_standard","I47";
;
CDS_LIB"mstr_standard"
BODY_TYPE"PLUMBING"
HDL_TAP"TRUE";
"B \NAC \NWC"6;
"S \NAC"
BN"11"88;
%"TAP"
"1","(-5975,2850)","0","mstr_standard","I48";
;
CDS_LIB"mstr_standard"
BODY_TYPE"PLUMBING"
HDL_TAP"TRUE";
"B \NAC \NWC"6;
"S \NAC"
BN"14"91;
%"TAP"
"1","(-5975,2800)","0","mstr_standard","I49";
;
CDS_LIB"mstr_standard"
BODY_TYPE"PLUMBING"
HDL_TAP"TRUE";
"B \NAC \NWC"6;
"S \NAC"
BN"13"90;
%"TAP"
"1","(-5975,2900)","0","mstr_standard","I50";
;
CDS_LIB"mstr_standard"
BODY_TYPE"PLUMBING"
HDL_TAP"TRUE";
"B \NAC \NWC"6;
"S \NAC"
BN"15"92;
%"TAP"
"1","(-5975,3000)","0","mstr_standard","I51";
;
CDS_LIB"mstr_standard"
BODY_TYPE"PLUMBING"
HDL_TAP"TRUE";
"B \NAC \NWC"6;
"S \NAC"
BN"17"94;
%"TAP"
"1","(-5975,2950)","0","mstr_standard","I52";
;
CDS_LIB"mstr_standard"
BODY_TYPE"PLUMBING"
HDL_TAP"TRUE";
"B \NAC \NWC"6;
"S \NAC"
BN"16"93;
%"TAP"
"1","(-5975,3150)","0","mstr_standard","I53";
;
CDS_LIB"mstr_standard"
BODY_TYPE"PLUMBING"
HDL_TAP"TRUE";
"B \NAC \NWC"6;
"S \NAC"
BN"20"97;
%"TAP"
"1","(-5975,3100)","0","mstr_standard","I54";
;
CDS_LIB"mstr_standard"
BODY_TYPE"PLUMBING"
HDL_TAP"TRUE";
"B \NAC \NWC"6;
"S \NAC"
BN"19"96;
%"TAP"
"1","(-5975,3050)","0","mstr_standard","I55";
;
CDS_LIB"mstr_standard"
BODY_TYPE"PLUMBING"
HDL_TAP"TRUE";
"B \NAC \NWC"6;
"S \NAC"
BN"18"95;
%"TAP"
"1","(-5975,3200)","0","mstr_standard","I56";
;
CDS_LIB"mstr_standard"
BODY_TYPE"PLUMBING"
HDL_TAP"TRUE";
"B \NAC \NWC"6;
"S \NAC"
BN"21"98;
%"TAP"
"1","(-5975,3250)","0","mstr_standard","I57";
;
CDS_LIB"mstr_standard"
BODY_TYPE"PLUMBING"
HDL_TAP"TRUE";
"B \NAC \NWC"6;
"S \NAC"
BN"22"99;
%"TAP"
"1","(-5975,3400)","0","mstr_standard","I58";
;
CDS_LIB"mstr_standard"
BODY_TYPE"PLUMBING"
HDL_TAP"TRUE";
"B \NAC \NWC"6;
"S \NAC"
BN"25"102;
%"TAP"
"1","(-5975,3350)","0","mstr_standard","I59";
;
CDS_LIB"mstr_standard"
BODY_TYPE"PLUMBING"
HDL_TAP"TRUE";
"B \NAC \NWC"6;
"S \NAC"
BN"24"101;
%"TAP"
"1","(-5975,3300)","0","mstr_standard","I60";
;
CDS_LIB"mstr_standard"
BODY_TYPE"PLUMBING"
HDL_TAP"TRUE";
"B \NAC \NWC"6;
"S \NAC"
BN"23"100;
%"TAP"
"1","(-5975,3450)","0","mstr_standard","I61";
;
CDS_LIB"mstr_standard"
BODY_TYPE"PLUMBING"
HDL_TAP"TRUE";
"B \NAC \NWC"6;
"S \NAC"
BN"26"103;
%"TAP"
"1","(-5975,3500)","0","mstr_standard","I62";
;
CDS_LIB"mstr_standard"
BODY_TYPE"PLUMBING"
HDL_TAP"TRUE";
"B \NAC \NWC"6;
"S \NAC"
BN"27"104;
%"TAP"
"1","(-5975,3650)","0","mstr_standard","I63";
;
CDS_LIB"mstr_standard"
BODY_TYPE"PLUMBING"
HDL_TAP"TRUE";
"B \NAC \NWC"6;
"S \NAC"
BN"30"107;
%"TAP"
"1","(-5975,3600)","0","mstr_standard","I64";
;
CDS_LIB"mstr_standard"
BODY_TYPE"PLUMBING"
HDL_TAP"TRUE";
"B \NAC \NWC"6;
"S \NAC"
BN"29"106;
%"TAP"
"1","(-5975,3550)","0","mstr_standard","I65";
;
CDS_LIB"mstr_standard"
BODY_TYPE"PLUMBING"
HDL_TAP"TRUE";
"B \NAC \NWC"6;
"S \NAC"
BN"28"105;
%"TAP"
"1","(-5975,3700)","0","mstr_standard","I66";
;
CDS_LIB"mstr_standard"
BODY_TYPE"PLUMBING"
HDL_TAP"TRUE";
"B \NAC \NWC"6;
"S \NAC"
BN"31"108;
%"TAP"
"1","(-7675,3800)","2","mstr_standard","I75";
;
CDS_LIB"mstr_standard"
BODY_TYPE"PLUMBING"
HDL_TAP"TRUE";
"B \NAC \NWC"1;
"S \NAC"
BN"4"175;
%"TAP"
"1","(-7675,3850)","2","mstr_standard","I76";
;
CDS_LIB"mstr_standard"
BODY_TYPE"PLUMBING"
HDL_TAP"TRUE";
"B \NAC \NWC"1;
"S \NAC"
BN"5"156;
%"TAP"
"1","(-7675,3900)","2","mstr_standard","I77";
;
CDS_LIB"mstr_standard"
BODY_TYPE"PLUMBING"
HDL_TAP"TRUE";
"B \NAC \NWC"1;
"S \NAC"
BN"6"157;
%"TAP"
"1","(-7675,3950)","2","mstr_standard","I78";
;
CDS_LIB"mstr_standard"
BODY_TYPE"PLUMBING"
HDL_TAP"TRUE";
"B \NAC \NWC"1;
"S \NAC"
BN"7"176;
%"TAP"
"1","(-7675,4650)","2","mstr_standard","I79";
;
CDS_LIB"mstr_standard"
BODY_TYPE"PLUMBING"
HDL_TAP"TRUE";
"B \NAC \NWC"3;
"S \NAC"
BN"0"170;
%"TAP"
"1","(-7675,4700)","2","mstr_standard","I80";
;
CDS_LIB"mstr_standard"
BODY_TYPE"PLUMBING"
HDL_TAP"TRUE";
"B \NAC \NWC"3;
"S \NAC"
BN"1"168;
%"TAP"
"1","(-7675,4750)","2","mstr_standard","I81";
;
CDS_LIB"mstr_standard"
BODY_TYPE"PLUMBING"
HDL_TAP"TRUE";
"B \NAC \NWC"3;
"S \NAC"
BN"2"166;
%"TAP"
"1","(-7675,4800)","2","mstr_standard","I82";
;
CDS_LIB"mstr_standard"
BODY_TYPE"PLUMBING"
HDL_TAP"TRUE";
"B \NAC \NWC"3;
"S \NAC"
BN"3"164;
%"TAP"
"1","(-7675,4850)","2","mstr_standard","I83";
;
CDS_LIB"mstr_standard"
BODY_TYPE"PLUMBING"
HDL_TAP"TRUE";
"B \NAC \NWC"3;
"S \NAC"
BN"4"162;
%"TAP"
"1","(-7675,4900)","2","mstr_standard","I84";
;
CDS_LIB"mstr_standard"
BODY_TYPE"PLUMBING"
HDL_TAP"TRUE";
"B \NAC \NWC"3;
"S \NAC"
BN"5"160;
%"TAP"
"1","(-7675,4950)","2","mstr_standard","I85";
;
CDS_LIB"mstr_standard"
BODY_TYPE"PLUMBING"
HDL_TAP"TRUE";
"B \NAC \NWC"3;
"S \NAC"
BN"6"158;
%"TAP"
"1","(-7675,5050)","2","mstr_standard","I86";
;
CDS_LIB"mstr_standard"
BODY_TYPE"PLUMBING"
HDL_TAP"TRUE";
"B \NAC \NWC"2;
"S \NAC"
BN"0"171;
%"TAP"
"1","(-7675,5100)","2","mstr_standard","I87";
;
CDS_LIB"mstr_standard"
BODY_TYPE"PLUMBING"
HDL_TAP"TRUE";
"B \NAC \NWC"2;
"S \NAC"
BN"1"169;
%"TAP"
"1","(-7675,5150)","2","mstr_standard","I88";
;
CDS_LIB"mstr_standard"
BODY_TYPE"PLUMBING"
HDL_TAP"TRUE";
"B \NAC \NWC"2;
"S \NAC"
BN"2"167;
%"TAP"
"1","(-7675,5200)","2","mstr_standard","I89";
;
CDS_LIB"mstr_standard"
BODY_TYPE"PLUMBING"
HDL_TAP"TRUE";
"B \NAC \NWC"2;
"S \NAC"
BN"3"165;
%"VCC_CORE"
"1","(-8450,3375)","0","mstr_symbols","I9";
;
HDL_POWER"P3V3_STBY"
CDS_LIB"mstr_symbols"
VOLTAGE"3.3"
ROOM"PVCCINFAON_CPU1_CTRL";
"A"22;
%"TAP"
"1","(-7675,5250)","2","mstr_standard","I90";
;
CDS_LIB"mstr_standard"
BODY_TYPE"PLUMBING"
HDL_TAP"TRUE";
"B \NAC \NWC"2;
"S \NAC"
BN"4"163;
%"TAP"
"1","(-7675,5300)","2","mstr_standard","I91";
;
CDS_LIB"mstr_standard"
BODY_TYPE"PLUMBING"
HDL_TAP"TRUE";
"B \NAC \NWC"2;
"S \NAC"
BN"5"161;
%"TAP"
"1","(-7675,5350)","2","mstr_standard","I92";
;
CDS_LIB"mstr_standard"
BODY_TYPE"PLUMBING"
HDL_TAP"TRUE";
"B \NAC \NWC"2;
"S \NAC"
BN"6"159;
%"TAP"
"1","(-5975,3800)","0","mstr_standard","I93";
;
CDS_LIB"mstr_standard"
BODY_TYPE"PLUMBING"
HDL_TAP"TRUE";
"B \NAC \NWC"5;
"S \NAC"
BN"0"109;
%"TAP"
"1","(-5975,3900)","0","mstr_standard","I94";
;
CDS_LIB"mstr_standard"
BODY_TYPE"PLUMBING"
HDL_TAP"TRUE";
"B \NAC \NWC"5;
"S \NAC"
BN"2"111;
%"TAP"
"1","(-5975,3850)","0","mstr_standard","I95";
;
CDS_LIB"mstr_standard"
BODY_TYPE"PLUMBING"
HDL_TAP"TRUE";
"B \NAC \NWC"5;
"S \NAC"
BN"1"110;
%"TAP"
"1","(-5975,3950)","0","mstr_standard","I96";
;
CDS_LIB"mstr_standard"
BODY_TYPE"PLUMBING"
HDL_TAP"TRUE";
"B \NAC \NWC"5;
"S \NAC"
BN"3"112;
%"TAP"
"1","(-5975,4000)","0","mstr_standard","I97";
;
CDS_LIB"mstr_standard"
BODY_TYPE"PLUMBING"
HDL_TAP"TRUE";
"B \NAC \NWC"5;
"S \NAC"
BN"4"113;
%"TAP"
"1","(-5975,4050)","0","mstr_standard","I98";
;
CDS_LIB"mstr_standard"
BODY_TYPE"PLUMBING"
HDL_TAP"TRUE";
"B \NAC \NWC"5;
"S \NAC"
BN"5"114;
%"TAP"
"1","(-5975,4100)","0","mstr_standard","I99";
;
CDS_LIB"mstr_standard"
BODY_TYPE"PLUMBING"
HDL_TAP"TRUE";
"B \NAC \NWC"5;
"S \NAC"
BN"6"115;
END.
